# BASEBOARD_FAB2 (Tioga Pass) — schematic netlist excerpt (pin names and nets, part order shuffled) for the footprints in the layout excerpt that follows; sources: Cadence DE-HDL packaged netlist, KiCad conversion of Wiwynn_Tioga_Pass_MB.brd

C2M21  CAP_A  1.0UF 6.3V 10% X6S  pkg 0402V  page 131 : A = P1V05_PCH_STBY ; B = GND
R1U44  1K82R2F-1-GP  1%  pkg SMD-RG  page 169 : \1\ = A_P5V_STBY_SCALED ; \2\ = GND

(kicad_pcb
	(version 20260206)
	(generator "pcbnew")
	(generator_version "10.0")
	(general
		(thickness 1.6)
		(legacy_teardrops no)
	)
	(paper "A4")
	(title_block
		(title "Wiwynn_Tioga_Pass_MB.brd")
		(comment 1 "Tioga Pass / footprints 4406-4407 of 4770")
	)
	(layers
		(0 "F.Cu" signal "TOP")
		(4 "In1.Cu" signal "L2GND")
		(6 "In2.Cu" signal "L3")
		(8 "In3.Cu" signal "L4GND")
		(10 "In4.Cu" signal "L5")
		(12 "In5.Cu" signal "L6GND")
		(14 "In6.Cu" signal "L7VCC")
		(16 "In7.Cu" signal "L8VCC")
		(18 "In8.Cu" signal "L9GND")
		(20 "In9.Cu" signal "L10")
		(22 "In10.Cu" signal "L11GND")
		(24 "In11.Cu" signal "L12")
		(26 "In12.Cu" signal "L13GND")
		(2 "B.Cu" signal "BOTTOM")
		(9 "F.Adhes" user "F.Adhesive")
		(11 "B.Adhes" user "B.Adhesive")
		(13 "F.Paste" user "Package Geometry/Pastemask Top")
		(15 "B.Paste" user "Package Geometry/Pastemask Bottom")
		(5 "F.SilkS" user "Ref Des/Silkscreen Top")
		(7 "B.SilkS" user "Ref Des/Silkscreen Bottom")
		(1 "F.Mask" user "Board Geometry/Soldermask Top")
		(3 "B.Mask" user "Board Geometry/Soldermask Bottom")
		(17 "Dwgs.User" user "User.Drawings")
		(19 "Cmts.User" user "User.Comments")
		(21 "Eco1.User" user "User.Eco1")
		(23 "Eco2.User" user "User.Eco2")
		(25 "Edge.Cuts" user "Board Geometry/Outline")
		(27 "Margin" user)
		(31 "F.CrtYd" user "Package Geometry/Place Bound Top")
		(29 "B.CrtYd" user "Package Geometry/Place Bound Bottom")
		(35 "F.Fab" user "Ref Des/Assembly Top")
		(33 "B.Fab" user "Ref Des/Assembly Bottom")
	)
	(footprint ""
		(layer "B.Cu")
		(at 390.93775 -113.45545)
		(property "Reference" "C2M21"
			(at 0 0 0)
			(layer "B.SilkS")
			(hide yes)
			(effects
				(font
					(size 1.27 1.27)
				)
				(justify mirror)
			)
		)
		(property "Value" ""
			(at 0 0 0)
			(layer "B.Fab")
			(effects
				(font
					(size 1.27 1.27)
				)
				(justify mirror)
			)
		)
		(duplicate_pad_numbers_are_jumpers no)
		(fp_rect
			(start 0.2794 0.9144)
			(end -0.2794 -0.1143)
			(stroke
				(width 0)
				(type default)
			)
			(fill no)
			(layer "B.CrtYd")
		)
		(fp_line
			(start -0.2794 -0.1143)
			(end -0.2794 0.9144)
			(stroke
				(width 0.1)
				(type default)
			)
			(layer "B.Fab")
		)
		(fp_line
			(start -0.2794 0.9144)
			(end 0.2794 0.9144)
			(stroke
				(width 0.1)
				(type default)
			)
			(layer "B.Fab")
		)
		(fp_line
			(start 0.2794 -0.1143)
			(end -0.2794 -0.1143)
			(stroke
				(width 0.1)
				(type default)
			)
			(layer "B.Fab")
		)
		(fp_line
			(start 0.2794 0.9144)
			(end 0.2794 -0.1143)
			(stroke
				(width 0.1)
				(type default)
			)
			(layer "B.Fab")
		)
		(pad "1" smd custom
			(at 0 0 270)
			(size 0.10414 0.10414)
			(layers "B.Cu" "B.Mask" "B.Paste")
			(net "P1V05_PCH_STBY")
			(options
				(clearance outline)
				(anchor circle)
			)
			(primitives
				(gr_poly
					(pts
						(xy -0.20828 -0.08636) (xy -0.20828 0.08636) (xy -0.08636 0.20828) (xy 0.086614 0.20828) (xy 0.20828 0.086614)
						(xy 0.20828 -0.08636) (xy 0.08636 -0.20828) (xy -0.08636 -0.20828)
					)
					(width 0)
					(fill yes)
				)
			)
		)
		(pad "2" smd custom
			(at 0 0.8001 270)
			(size 0.10414 0.10414)
			(layers "B.Cu" "B.Mask" "B.Paste")
			(net "GND")
			(options
				(clearance outline)
				(anchor circle)
			)
			(primitives
				(gr_poly
					(pts
						(xy -0.20828 -0.08636) (xy -0.20828 0.08636) (xy -0.08636 0.20828) (xy 0.086614 0.20828) (xy 0.20828 0.086614)
						(xy 0.20828 -0.08636) (xy 0.08636 -0.20828) (xy -0.08636 -0.20828)
					)
					(width 0)
					(fill yes)
				)
			)
		)
		(zone
			(layer "B.Cu")
			(hatch none 0.5)
			(connect_pads
				(clearance 0)
			)
			(min_thickness 0.25)
			(keepout
				(tracks not_allowed)
				(vias allowed)
				(pads allowed)
				(copperpour not_allowed)
				(footprints allowed)
			)
			(placement
				(enabled no)
				(sheetname "")
			)
			(fill
				(thermal_gap 0.5)
				(thermal_bridge_width 0.5)
				(island_removal_mode 0)
			)
			(polygon
				(pts
					(xy 391.02538 -113.2459) (xy 391.02538 -112.8649) (xy 390.85012 -112.8649) (xy 390.849866 -113.2459)
				)
			)
		)
		(zone
			(layer "B.Cu")
			(hatch none 0.5)
			(connect_pads
				(clearance 0)
			)
			(min_thickness 0.25)
			(keepout
				(tracks allowed)
				(vias not_allowed)
				(pads allowed)
				(copperpour not_allowed)
				(footprints allowed)
			)
			(placement
				(enabled no)
				(sheetname "")
			)
			(fill
				(thermal_gap 0.5)
				(thermal_bridge_width 0.5)
				(island_removal_mode 0)
			)
			(polygon
				(pts
					(xy 391.02538 -113.2459) (xy 391.02538 -112.8649) (xy 390.85012 -112.8649) (xy 390.849866 -113.2459)
				)
			)
		)
	)
	(footprint ""
		(layer "B.Cu")
		(at 402.043646 -24.838152)
		(property "Reference" "R1U44"
			(at 0 0 0)
			(layer "B.SilkS")
			(hide yes)
			(effects
				(font
					(size 1.27 1.27)
				)
				(justify mirror)
			)
		)
		(property "Value" "*"
			(at -0.064008 -4.108196 0)
			(unlocked yes)
			(layer "B.Fab")
			(hide yes)
			(effects
				(font
					(size 1.27 1.016)
					(thickness 0.1524)
				)
				(justify mirror)
			)
		)
		(property "Device Type" "1K82R2F-1-GP_SMD-RG-1K82R2F-1-A"
			(at -0.064008 -5.632196 0)
			(unlocked yes)
			(layer "B.Fab")
			(hide yes)
			(effects
				(font
					(size 1.27 1.016)
					(thickness 0.1524)
				)
				(justify mirror)
			)
		)
		(duplicate_pad_numbers_are_jumpers no)
		(fp_line
			(start -0.508 -0.9398)
			(end 0.508 -0.9398)
			(stroke
				(width 0.1524)
				(type default)
			)
			(layer "B.SilkS")
		)
		(fp_line
			(start 0.508 -0.9398)
			(end 0.508 0.9398)
			(stroke
				(width 0.1524)
				(type default)
			)
			(layer "B.SilkS")
		)
		(fp_rect
			(start 0.508 0.9398)
			(end -0.508 -0.9398)
			(stroke
				(width 0)
				(type default)
			)
			(fill no)
			(layer "B.CrtYd")
		)
		(fp_rect
			(start 0.508 0.9398)
			(end -0.508 -0.9398)
			(stroke
				(width 0)
				(type default)
			)
			(fill no)
			(layer "B.Fab")
		)
		(pad "1" smd custom
			(at 0 -0.4445 180)
			(size 0.1397 0.1397)
			(layers "B.Cu" "B.Mask" "B.Paste")
			(net "A_P5V_STBY_SCALED")
			(options
				(clearance outline)
				(anchor circle)
			)
			(primitives
				(gr_poly
					(pts
						(arc
							(start -0.1778 0.2794)
							(mid -0.249642 0.249642)
							(end -0.2794 0.1778)
						)
						(arc
							(start -0.2794 -0.1778)
							(mid -0.249642 -0.249642)
							(end -0.1778 -0.2794)
						)
						(arc
							(start 0.1778 -0.2794)
							(mid 0.249642 -0.249642)
							(end 0.2794 -0.1778)
						)
						(arc
							(start 0.2794 0.1778)
							(mid 0.249642 0.249642)
							(end 0.1778 0.2794)
						)
					)
					(width 0)
					(fill yes)
				)
			)
		)
		(pad "2" smd custom
			(at 0 0.4445 180)
			(size 0.1397 0.1397)
			(layers "B.Cu" "B.Mask" "B.Paste")
			(net "GND")
			(options
				(clearance outline)
				(anchor circle)
			)
			(primitives
				(gr_poly
					(pts
						(arc
							(start -0.1778 0.2794)
							(mid -0.249642 0.249642)
							(end -0.2794 0.1778)
						)
						(arc
							(start -0.2794 -0.1778)
							(mid -0.249642 -0.249642)
							(end -0.1778 -0.2794)
						)
						(arc
							(start 0.1778 -0.2794)
							(mid 0.249642 -0.249642)
							(end 0.2794 -0.1778)
						)
						(arc
							(start 0.2794 0.1778)
							(mid 0.249642 0.249642)
							(end 0.1778 0.2794)
						)
					)
					(width 0)
					(fill yes)
				)
			)
		)
	)
)
